(kicad_pcb
	(version 20241229)
	(generator "pcbnew")
	(generator_version "9.0")
	(general
		(thickness 1.711)
		(legacy_teardrops no)
	)
	(paper "A4")
	(title_block
		(title "Antmicro Baseboard for Jetson AGX Thor")
		(date "2026-02-18")
		(rev "1.1.0")
		(company "Antmicro Ltd")
		(comment 1 "www.antmicro.com")
		(comment 9 "footprints 629-633 of 1170")
	)
	(layers
		(0 "F.Cu" signal)
		(4 "In1.Cu" signal)
		(6 "In2.Cu" signal)
		(8 "In3.Cu" signal)
		(10 "In4.Cu" jumper)
		(12 "In5.Cu" signal)
		(14 "In6.Cu" signal)
		(16 "In7.Cu" signal)
		(18 "In8.Cu" signal)
		(2 "B.Cu" signal)
		(9 "F.Adhes" user "F.Adhesive")
		(11 "B.Adhes" user "B.Adhesive")
		(13 "F.Paste" user)
		(15 "B.Paste" user)
		(5 "F.SilkS" user "F.Silkscreen")
		(7 "B.SilkS" user "B.Silkscreen")
		(1 "F.Mask" user)
		(3 "B.Mask" user)
		(17 "Dwgs.User" user "User.Drawings")
		(19 "Cmts.User" user "User.Comments")
		(21 "Eco1.User" user "User.Eco1")
		(23 "Eco2.User" user "User.Eco2")
		(25 "Edge.Cuts" user)
		(27 "Margin" user)
		(31 "F.CrtYd" user "F.Courtyard")
		(29 "B.CrtYd" user "B.Courtyard")
		(35 "F.Fab" user)
		(33 "B.Fab" user)
	)
	(footprint "antmicro-footprints:C_0402_1005Metric"
		(layer "B.Cu")
		(at 230.07 113.8 180)
		(descr "Capacitor SMD 0402")
		(tags "capacitor SMD 0402")
		(property "Reference" "C80"
			(at 0.9 -0.4 0)
			(layer "B.SilkS")
			(effects
				(font
					(size 0.7 0.7)
					(thickness 0.15)
				)
				(justify left bottom mirror)
			)
		)
		(property "Value" "C_100n_0402"
			(at -1.022927 -2.155213 0)
			(layer "B.Fab")
			(effects
				(font
					(size 0.7 0.7)
					(thickness 0.15)
				)
				(justify left bottom mirror)
			)
		)
		(property "Datasheet" "https://www.murata.com/products/productdetail?partno=GRM155R61H104KE14%23"
			(at 0 0 0)
			(layer "B.Fab")
			(hide yes)
			(effects
				(font
					(size 1.27 1.27)
					(thickness 0.15)
				)
				(justify mirror)
			)
		)
		(property "Description" "SMD Multilayer Ceramic Capacitor, 0.1 µF, 50 V, 0402 [1005 Metric], ± 10%, X5R, GRM Series"
			(at 0 0 0)
			(layer "B.Fab")
			(hide yes)
			(effects
				(font
					(size 1.27 1.27)
					(thickness 0.15)
				)
				(justify mirror)
			)
		)
		(property "Manufacturer" "Murata"
			(at 0 0 0)
			(unlocked yes)
			(layer "B.Fab")
			(hide yes)
			(effects
				(font
					(size 1 1)
					(thickness 0.15)
				)
				(justify mirror)
			)
		)
		(property "MPN" "GRM155R61H104KE14D"
			(at 0 0 0)
			(unlocked yes)
			(layer "B.Fab")
			(hide yes)
			(effects
				(font
					(size 1 1)
					(thickness 0.15)
				)
				(justify mirror)
			)
		)
		(property "Val" "100n"
			(at 0 0 0)
			(unlocked yes)
			(layer "B.Fab")
			(hide yes)
			(effects
				(font
					(size 1 1)
					(thickness 0.15)
				)
				(justify mirror)
			)
		)
		(property "License" "Apache-2.0"
			(at 0 0 0)
			(unlocked yes)
			(layer "B.Fab")
			(hide yes)
			(effects
				(font
					(size 1 1)
					(thickness 0.15)
				)
				(justify mirror)
			)
		)
		(property "Author" "Antmicro"
			(at 0 0 0)
			(unlocked yes)
			(layer "B.Fab")
			(hide yes)
			(effects
				(font
					(size 1 1)
					(thickness 0.15)
				)
				(justify mirror)
			)
		)
		(property "Voltage" "50V"
			(at 0 0 0)
			(unlocked yes)
			(layer "B.Fab")
			(hide yes)
			(effects
				(font
					(size 1 1)
					(thickness 0.15)
				)
				(justify mirror)
			)
		)
		(property "Dielectric" "X5R"
			(at 0 0 0)
			(unlocked yes)
			(layer "B.Fab")
			(hide yes)
			(effects
				(font
					(size 1 1)
					(thickness 0.15)
				)
				(justify mirror)
			)
		)
		(sheetname "/USB Hub/")
		(sheetfile "usb_hub.kicad_sch")
		(attr smd)
		(fp_poly
			(pts
				(xy -0.925 0.47) (xy 0.925 0.47) (xy 0.925 -0.47) (xy -0.925 -0.47)
			)
			(stroke
				(width 0.05)
				(type default)
			)
			(fill no)
			(layer "B.CrtYd")
		)
		(fp_line
			(start 0.504 0.25)
			(end 0.504 -0.248)
			(stroke
				(width 0.15)
				(type solid)
			)
			(layer "B.Fab")
		)
		(fp_line
			(start 0.504 -0.248)
			(end -0.494 -0.248)
			(stroke
				(width 0.15)
				(type solid)
			)
			(layer "B.Fab")
		)
		(fp_line
			(start -0.494 0.25)
			(end 0.504 0.25)
			(stroke
				(width 0.15)
				(type solid)
			)
			(layer "B.Fab")
		)
		(fp_line
			(start -0.494 -0.248)
			(end -0.494 0.25)
			(stroke
				(width 0.15)
				(type solid)
			)
			(layer "B.Fab")
		)
		(fp_text user "License: Apache-2.0"
			(at -0.939 -5.799 0)
			(layer "B.Fab")
			(effects
				(font
					(size 0.7 0.7)
					(thickness 0.15)
				)
				(justify left bottom mirror)
			)
		)
		(fp_text user "Author: Antmicro"
			(at -0.939 -3.399 0)
			(layer "B.Fab")
			(effects
				(font
					(size 0.7 0.7)
					(thickness 0.15)
				)
				(justify left bottom mirror)
			)
		)
		(fp_text user "${REFERENCE}"
			(at -0.939 -4.599 0)
			(layer "B.Fab")
			(effects
				(font
					(size 0.7 0.7)
					(thickness 0.15)
				)
				(justify left bottom mirror)
			)
		)
		(pad "1" smd roundrect
			(at -0.48 0 180)
			(size 0.59 0.64)
			(layers "B.Cu" "B.Mask" "B.Paste")
			(roundrect_rratio 0.25)
			(net 71 "/USB Hub/USBC3_VBUS")
			(pintype "passive")
		)
		(pad "2" smd roundrect
			(at 0.48 0 180)
			(size 0.59 0.64)
			(layers "B.Cu" "B.Mask" "B.Paste")
			(roundrect_rratio 0.25)
			(net 1 "GND")
			(pintype "passive")
		)
	)
	(footprint "antmicro-footprints:R_0402_1005Metric"
		(layer "B.Cu")
		(at 124.6 107.8 180)
		(descr "Resistor SMD 0402")
		(tags "resistor SMD 0402")
		(property "Reference" "R207"
			(at -3.9 -0.36 0)
			(layer "B.SilkS")
			(effects
				(font
					(size 0.7 0.7)
					(thickness 0.15)
				)
				(justify left bottom mirror)
			)
		)
		(property "Value" "R_0R_0402"
			(at -1.011843 -1.772046 0)
			(layer "B.Fab")
			(effects
				(font
					(size 0.7 0.7)
					(thickness 0.15)
				)
				(justify left bottom mirror)
			)
		)
		(property "Datasheet" "https://industrial.panasonic.com/cdbs/www-data/pdf/RDA0000/AOA0000C301.pdf"
			(at 0 0 0)
			(layer "B.Fab")
			(hide yes)
			(effects
				(font
					(size 1.27 1.27)
					(thickness 0.15)
				)
				(justify mirror)
			)
		)
		(property "Description" "SMD Chip Resistor, Jumper, 0 ohm, 100 mW, 0402 [1005 Metric], Thick Film, General Purpose"
			(at 0 0 0)
			(layer "B.Fab")
			(hide yes)
			(effects
				(font
					(size 1.27 1.27)
					(thickness 0.15)
				)
				(justify mirror)
			)
		)
		(property "MPN" "ERJ2GE0R00X"
			(at 0 0 0)
			(unlocked yes)
			(layer "B.Fab")
			(hide yes)
			(effects
				(font
					(size 1 1)
					(thickness 0.15)
				)
				(justify mirror)
			)
		)
		(property "Manufacturer" "Panasonic"
			(at 0 0 0)
			(unlocked yes)
			(layer "B.Fab")
			(hide yes)
			(effects
				(font
					(size 1 1)
					(thickness 0.15)
				)
				(justify mirror)
			)
		)
		(property "License" "Apache-2.0"
			(at 0 0 0)
			(unlocked yes)
			(layer "B.Fab")
			(hide yes)
			(effects
				(font
					(size 1 1)
					(thickness 0.15)
				)
				(justify mirror)
			)
		)
		(property "Author" "Antmicro"
			(at 0 0 0)
			(unlocked yes)
			(layer "B.Fab")
			(hide yes)
			(effects
				(font
					(size 1 1)
					(thickness 0.15)
				)
				(justify mirror)
			)
		)
		(property "Val" "0R"
			(at 0 0 0)
			(unlocked yes)
			(layer "B.Fab")
			(hide yes)
			(effects
				(font
					(size 1 1)
					(thickness 0.15)
				)
				(justify mirror)
			)
		)
		(property "Tolerance" "~"
			(at 0 0 0)
			(unlocked yes)
			(layer "B.Fab")
			(hide yes)
			(effects
				(font
					(size 1 1)
					(thickness 0.15)
				)
				(justify mirror)
			)
		)
		(property "Current" "1A"
			(at 0 0 0)
			(unlocked yes)
			(layer "B.Fab")
			(hide yes)
			(effects
				(font
					(size 1 1)
					(thickness 0.15)
				)
				(justify mirror)
			)
		)
		(sheetname "/M.2/")
		(sheetfile "m2.kicad_sch")
		(attr smd)
		(fp_poly
			(pts
				(xy -0.925 0.47) (xy 0.925 0.47) (xy 0.925 -0.47) (xy -0.925 -0.47)
			)
			(stroke
				(width 0.05)
				(type default)
			)
			(fill no)
			(layer "B.CrtYd")
		)
		(fp_poly
			(pts
				(xy -0.5 0.25) (xy 0.5 0.25) (xy 0.5 -0.25) (xy -0.5 -0.25)
			)
			(stroke
				(width 0.15)
				(type solid)
			)
			(fill no)
			(layer "B.Fab")
		)
		(fp_text user "License: Apache-2.0"
			(at -0.949999 -5.169 0)
			(layer "B.Fab")
			(effects
				(font
					(size 0.7 0.7)
					(thickness 0.15)
				)
				(justify left bottom mirror)
			)
		)
		(fp_text user "${REFERENCE}"
			(at -0.95 -3.168 0)
			(layer "B.Fab")
			(effects
				(font
					(size 0.7 0.7)
					(thickness 0.15)
				)
				(justify left bottom mirror)
			)
		)
		(fp_text user "Author: Antmicro"
			(at -0.95 -4.169 0)
			(layer "B.Fab")
			(effects
				(font
					(size 0.7 0.7)
					(thickness 0.15)
				)
				(justify left bottom mirror)
			)
		)
		(pad "1" smd roundrect
			(at -0.48 0 180)
			(size 0.59 0.64)
			(layers "B.Cu" "B.Mask" "B.Paste")
			(roundrect_rratio 0.25)
			(net 751 "/M.2/PCIe_{C5x4}.~{CLKREQ}")
			(pintype "passive")
		)
		(pad "2" smd roundrect
			(at 0.48 0 180)
			(size 0.59 0.64)
			(layers "B.Cu" "B.Mask" "B.Paste")
			(roundrect_rratio 0.25)
			(net 825 "/M.2/~{CLKREQ_M}")
			(pintype "passive")
		)
	)
	(footprint "antmicro-footprints:SOD-523"
		(layer "B.Cu")
		(at 230.07 100.9 180)
		(property "Reference" "D50"
			(at 1 -0.4 0)
			(layer "B.SilkS")
			(effects
				(font
					(size 0.7 0.7)
					(thickness 0.15)
				)
				(justify left bottom mirror)
			)
		)
		(property "Value" "PESD5Z5.0F"
			(at 0 -1.499 0)
			(layer "B.Fab")
			(effects
				(font
					(size 0.7 0.7)
					(thickness 0.15)
				)
				(justify left bottom mirror)
			)
		)
		(property "Datasheet" "https://assets.nexperia.com/documents/data-sheet/PESD5Z5_0.pdf"
			(at 0 0 0)
			(layer "B.Fab")
			(hide yes)
			(effects
				(font
					(size 1.27 1.27)
					(thickness 0.15)
				)
				(justify mirror)
			)
		)
		(property "Description" "Unidirectional TVS, 30 kV,  SOD-523, 5 V, 89 pF"
			(at 0 0 0)
			(layer "B.Fab")
			(hide yes)
			(effects
				(font
					(size 1.27 1.27)
					(thickness 0.15)
				)
				(justify mirror)
			)
		)
		(property "Manufacturer" "Nexperia"
			(at 0 0 180)
			(unlocked yes)
			(layer "B.Fab")
			(hide yes)
			(effects
				(font
					(size 1 1)
					(thickness 0.15)
				)
				(justify mirror)
			)
		)
		(property "MPN" "PESD5Z5.0F"
			(at 0 0 180)
			(unlocked yes)
			(layer "B.Fab")
			(hide yes)
			(effects
				(font
					(size 1 1)
					(thickness 0.15)
				)
				(justify mirror)
			)
		)
		(property "Author" "Antmicro"
			(at 0 0 180)
			(unlocked yes)
			(layer "B.Fab")
			(hide yes)
			(effects
				(font
					(size 1 1)
					(thickness 0.15)
				)
				(justify mirror)
			)
		)
		(property "License" "Apache-2.0"
			(at 0 0 180)
			(unlocked yes)
			(layer "B.Fab")
			(hide yes)
			(effects
				(font
					(size 1 1)
					(thickness 0.15)
				)
				(justify mirror)
			)
		)
		(sheetname "/Recovery USB/")
		(sheetfile "recovery_usb.kicad_sch")
		(attr smd)
		(fp_line
			(start -0.35 0.5)
			(end -0.35 -0.5)
			(stroke
				(width 0.15)
				(type solid)
			)
			(layer "B.SilkS")
		)
		(fp_rect
			(start -1 0.6)
			(end 1 -0.6)
			(stroke
				(width 0.05)
				(type solid)
			)
			(fill no)
			(layer "B.CrtYd")
		)
		(fp_line
			(start 0.65 0.425)
			(end 0.65 -0.423)
			(stroke
				(width 0.15)
				(type solid)
			)
			(layer "B.Fab")
		)
		(fp_line
			(start -0.35 0.4)
			(end -0.35 -0.4)
			(stroke
				(width 0.15)
				(type solid)
			)
			(layer "B.Fab")
		)
		(fp_line
			(start -0.652 0.425)
			(end 0.65 0.425)
			(stroke
				(width 0.15)
				(type solid)
			)
			(layer "B.Fab")
		)
		(fp_line
			(start -0.652 -0.423)
			(end 0.65 -0.423)
			(stroke
				(width 0.15)
				(type solid)
			)
			(layer "B.Fab")
		)
		(fp_line
			(start -0.652 -0.423)
			(end -0.652 0.425)
			(stroke
				(width 0.15)
				(type solid)
			)
			(layer "B.Fab")
		)
		(fp_text user "Author: Antmicro"
			(at -1.276 -4.7 0)
			(layer "B.Fab")
			(effects
				(font
					(size 0.7 0.7)
					(thickness 0.15)
				)
				(justify left bottom mirror)
			)
		)
		(fp_text user "${REFERENCE}"
			(at -1.276 -3.499 0)
			(layer "B.Fab")
			(effects
				(font
					(size 0.7 0.7)
					(thickness 0.15)
				)
				(justify left bottom mirror)
			)
		)
		(fp_text user "License: Apache-2.0"
			(at -1.276 -5.9 0)
			(layer "B.Fab")
			(effects
				(font
					(size 0.7 0.7)
					(thickness 0.15)
				)
				(justify left bottom mirror)
			)
		)
		(pad "1" smd roundrect
			(at -0.701 0 180)
			(size 0.5 0.6)
			(layers "B.Cu" "B.Mask" "B.Paste")
			(roundrect_rratio 0.25)
			(net 287 "/Recovery USB/USBC2_VBUS")
			(pinfunction "C")
			(pintype "passive")
		)
		(pad "2" smd roundrect
			(at 0.699 0 180)
			(size 0.5 0.6)
			(layers "B.Cu" "B.Mask" "B.Paste")
			(roundrect_rratio 0.25)
			(net 1 "GND")
			(pinfunction "A")
			(pintype "passive")
		)
	)
	(footprint "antmicro-footprints:TP_SMD_0.75mm"
		(layer "B.Cu")
		(at 191.8 80.6815)
		(property "Reference" "TP14"
			(at 0.4 -3.2815 90)
			(layer "B.SilkS")
			(effects
				(font
					(size 0.7 0.7)
					(thickness 0.15)
				)
				(justify left bottom mirror)
			)
		)
		(property "Value" "TP_0.75mm_SMD"
			(at 0 -1.2 180)
			(layer "B.Fab")
			(effects
				(font
					(size 0.7 0.7)
					(thickness 0.15)
				)
				(justify left bottom mirror)
			)
		)
		(property "Description" "SMT test point"
			(at 0 0 180)
			(layer "B.Fab")
			(hide yes)
			(effects
				(font
					(size 1.27 1.27)
					(thickness 0.15)
				)
				(justify mirror)
			)
		)
		(property "MPN" ""
			(at 0 0 180)
			(unlocked yes)
			(layer "B.Fab")
			(hide yes)
			(effects
				(font
					(size 1 1)
					(thickness 0.15)
				)
				(justify mirror)
			)
		)
		(property "Manufacturer" ""
			(at 0 0 180)
			(unlocked yes)
			(layer "B.Fab")
			(hide yes)
			(effects
				(font
					(size 1 1)
					(thickness 0.15)
				)
				(justify mirror)
			)
		)
		(property "Author" "Antmicro"
			(at 0 0 180)
			(unlocked yes)
			(layer "B.Fab")
			(hide yes)
			(effects
				(font
					(size 1 1)
					(thickness 0.15)
				)
				(justify mirror)
			)
		)
		(property "License" "Apache-2.0"
			(at 0 0 180)
			(unlocked yes)
			(layer "B.Fab")
			(hide yes)
			(effects
				(font
					(size 1 1)
					(thickness 0.15)
				)
				(justify mirror)
			)
		)
		(sheetname "/USB Debug, PD/")
		(sheetfile "usb_debug_pd.kicad_sch")
		(attr exclude_from_pos_files exclude_from_bom)
		(fp_circle
			(center 0 0)
			(end 0.475 0)
			(stroke
				(width 0.05)
				(type default)
			)
			(fill no)
			(layer "B.CrtYd")
		)
		(fp_text user "Author: Antmicro"
			(at -0.4 -3.901 180)
			(layer "B.Fab")
			(effects
				(font
					(size 0.7 0.7)
					(thickness 0.15)
				)
				(justify left bottom mirror)
			)
		)
		(fp_text user "${REFERENCE}"
			(at -0.4 -2.7 180)
			(layer "B.Fab")
			(effects
				(font
					(size 0.7 0.7)
					(thickness 0.15)
				)
				(justify left bottom mirror)
			)
		)
		(fp_text user "License: Apache-2.0"
			(at -0.4 -5.101 180)
			(layer "B.Fab")
			(effects
				(font
					(size 0.7 0.7)
					(thickness 0.15)
				)
				(justify left bottom mirror)
			)
		)
		(pad "1" smd circle
			(at 0 0)
			(size 0.75 0.75)
			(layers "B.Cu" "B.Mask")
			(net 947 "/USB Debug, PD/PDC_I2C2_SCL")
			(pinfunction "1")
			(pintype "passive")
		)
	)
	(footprint "antmicro-footprints:C_0402_1005Metric"
		(layer "B.Cu")
		(at 110.25 100.501)
		(descr "Capacitor SMD 0402")
		(tags "capacitor SMD 0402")
		(property "Reference" "C183"
			(at -0.95 -0.301 0)
			(layer "B.SilkS")
			(effects
				(font
					(size 0.7 0.7)
					(thickness 0.15)
				)
				(justify left top mirror)
			)
		)
		(property "Value" "C_220n_0402"
			(at -1.022927 -2.155213 0)
			(layer "B.Fab")
			(effects
				(font
					(size 0.7 0.7)
					(thickness 0.15)
				)
				(justify right top mirror)
			)
		)
		(property "Datasheet" "https://www.yageo.com/en/Chart/Download/pdf/CC0402KRX5R6BB224"
			(at 0 0 0)
			(layer "B.Fab")
			(hide yes)
			(effects
				(font
					(size 1.27 1.27)
					(thickness 0.15)
				)
				(justify mirror)
			)
		)
		(property "Description" "SMD Multilayer Ceramic Capacitor, 0.22 µF, 10 V, 0402 [1005 Metric], ± 10%, X5R, CC Series"
			(at 0 0 0)
			(layer "B.Fab")
			(hide yes)
			(effects
				(font
					(size 1.27 1.27)
					(thickness 0.15)
				)
				(justify mirror)
			)
		)
		(property "MPN" "CC0402KRX5R6BB224"
			(at 0 0 0)
			(unlocked yes)
			(layer "B.Fab")
			(hide yes)
			(effects
				(font
					(size 1 1)
					(thickness 0.15)
				)
				(justify mirror)
			)
		)
		(property "Val" "220n"
			(at 0 0 0)
			(unlocked yes)
			(layer "B.Fab")
			(hide yes)
			(effects
				(font
					(size 1 1)
					(thickness 0.15)
				)
				(justify mirror)
			)
		)
		(property "Voltage" "25V"
			(at 0 0 0)
			(unlocked yes)
			(layer "B.Fab")
			(hide yes)
			(effects
				(font
					(size 1 1)
					(thickness 0.15)
				)
				(justify mirror)
			)
		)
		(property "Dielectric" "X7R"
			(at 0 0 0)
			(unlocked yes)
			(layer "B.Fab")
			(hide yes)
			(effects
				(font
					(size 1 1)
					(thickness 0.15)
				)
				(justify mirror)
			)
		)
		(property "Manufacturer" "YAGEO"
			(at 0 0 0)
			(unlocked yes)
			(layer "B.Fab")
			(hide yes)
			(effects
				(font
					(size 1 1)
					(thickness 0.15)
				)
				(justify mirror)
			)
		)
		(property "License" "Apache-2.0"
			(at 0 0 0)
			(unlocked yes)
			(layer "B.Fab")
			(hide yes)
			(effects
				(font
					(size 1 1)
					(thickness 0.15)
				)
				(justify mirror)
			)
		)
		(property "Author" "Antmicro"
			(at 0 0 0)
			(unlocked yes)
			(layer "B.Fab")
			(hide yes)
			(effects
				(font
					(size 1 1)
					(thickness 0.15)
				)
				(justify mirror)
			)
		)
		(property "Public" "False"
			(at 0 0 0)
			(unlocked yes)
			(layer "B.Fab")
			(hide yes)
			(effects
				(font
					(size 1 1)
					(thickness 0.15)
				)
				(justify mirror)
			)
		)
		(sheetname "/M.2/")
		(sheetfile "m2.kicad_sch")
		(attr smd)
		(fp_poly
			(pts
				(xy -0.925 0.47) (xy -0.925 -0.47) (xy 0.925 -0.47) (xy 0.925 0.47)
			)
			(stroke
				(width 0.05)
				(type default)
			)
			(fill no)
			(layer "B.CrtYd")
		)
		(fp_line
			(start -0.494 -0.248)
			(end -0.494 0.25)
			(stroke
				(width 0.15)
				(type solid)
			)
			(layer "B.Fab")
		)
		(fp_line
			(start -0.494 0.25)
			(end 0.504 0.25)
			(stroke
				(width 0.15)
				(type solid)
			)
			(layer "B.Fab")
		)
		(fp_line
			(start 0.504 -0.248)
			(end -0.494 -0.248)
			(stroke
				(width 0.15)
				(type solid)
			)
			(layer "B.Fab")
		)
		(fp_line
			(start 0.504 0.25)
			(end 0.504 -0.248)
			(stroke
				(width 0.15)
				(type solid)
			)
			(layer "B.Fab")
		)
		(fp_text user "Author: Antmicro"
			(at -0.939 -3.399 0)
			(layer "B.Fab")
			(effects
				(font
					(size 0.7 0.7)
					(thickness 0.15)
				)
				(justify right top mirror)
			)
		)
		(fp_text user "${REFERENCE}"
			(at -0.939 -4.599 0)
			(layer "B.Fab")
			(effects
				(font
					(size 0.7 0.7)
					(thickness 0.15)
				)
				(justify right top mirror)
			)
		)
		(fp_text user "License: Apache-2.0"
			(at -0.939 -5.799 0)
			(layer "B.Fab")
			(effects
				(font
					(size 0.7 0.7)
					(thickness 0.15)
				)
				(justify right top mirror)
			)
		)
		(pad "1" smd roundrect
			(at -0.48 0)
			(size 0.59 0.64)
			(layers "B.Cu" "B.Mask" "B.Paste")
			(roundrect_rratio 0.25)
			(net 400 "/M.2/PCIe_{C5x4}.TX2+")
			(pintype "passive")
		)
		(pad "2" smd roundrect
			(at 0.48 0)
			(size 0.59 0.64)
			(layers "B.Cu" "B.Mask" "B.Paste")
			(roundrect_rratio 0.25)
			(net 399 "/M.2/M2_M_PET2_P")
			(pintype "passive")
		)
	)
)
